(kicad_pcb
	(version 20260206)
	(generator "pcbnew")
	(generator_version "10.0")
	(general
		(thickness 1.6)
		(legacy_teardrops no)
	)
	(paper "A4")
	(title_block
		(title "12092022_DA0F0TMDCD0_F0T_Management_Board_D_brd_V3_OCP.brd")
		(comment 1 "Grand Teton / footprints 733-738 of 1440")
	)
	(layers
		(0 "F.Cu" signal "TOP")
		(4 "In1.Cu" signal "GND")
		(6 "In2.Cu" signal "IN1")
		(8 "In3.Cu" signal "GND1")
		(10 "In4.Cu" signal "IN2")
		(12 "In5.Cu" signal "VCC")
		(14 "In6.Cu" signal "VCC1")
		(16 "In7.Cu" signal "IN3")
		(18 "In8.Cu" signal "GND2")
		(20 "In9.Cu" signal "IN4")
		(22 "In10.Cu" signal "GND3")
		(2 "B.Cu" signal "BOTTOM")
		(9 "F.Adhes" user "F.Adhesive")
		(11 "B.Adhes" user "B.Adhesive")
		(13 "F.Paste" user "Package Geometry/Pastemask Top")
		(15 "B.Paste" user "Package Geometry/Pastemask Bottom")
		(5 "F.SilkS" user "Ref Des/Silkscreen Top")
		(7 "B.SilkS" user "Ref Des/Silkscreen Bottom")
		(1 "F.Mask" user "Board Geometry/Soldermask Top")
		(3 "B.Mask" user "Board Geometry/Soldermask Bottom")
		(17 "Dwgs.User" user "User.Drawings")
		(19 "Cmts.User" user "User.Comments")
		(21 "Eco1.User" user "User.Eco1")
		(23 "Eco2.User" user "User.Eco2")
		(25 "Edge.Cuts" user "Board Geometry/Outline")
		(27 "Margin" user)
		(31 "F.CrtYd" user "Package Geometry/Place Bound Top")
		(29 "B.CrtYd" user "Package Geometry/Place Bound Bottom")
		(35 "F.Fab" user "Ref Des/Assembly Top")
		(33 "B.Fab" user "Ref Des/Assembly Bottom")
	)
	(footprint ""
		(layer "B.Cu")
		(at 15.367 -106.426 90)
		(property "Reference" "R899"
			(at 0 0 90)
			(layer "B.SilkS")
			(hide yes)
			(effects
				(font
					(size 1.27 1.27)
				)
				(justify mirror)
			)
		)
		(property "Value" ""
			(at 0 0 90)
			(layer "B.Fab")
			(effects
				(font
					(size 1.27 1.27)
				)
				(justify mirror)
			)
		)
		(duplicate_pad_numbers_are_jumpers no)
		(fp_line
			(start 0.7874 -0.4064)
			(end -0.7874 -0.4064)
			(stroke
				(width 0.1524)
				(type default)
			)
			(layer "B.SilkS")
		)
		(fp_line
			(start -0.7874 -0.4064)
			(end -0.7874 0.4064)
			(stroke
				(width 0.1524)
				(type default)
			)
			(layer "B.SilkS")
		)
		(fp_line
			(start 0.7874 0.4064)
			(end 0.7874 -0.4064)
			(stroke
				(width 0.1524)
				(type default)
			)
			(layer "B.SilkS")
		)
		(fp_line
			(start -0.7874 0.4064)
			(end 0.7874 0.4064)
			(stroke
				(width 0.1524)
				(type default)
			)
			(layer "B.SilkS")
		)
		(fp_line
			(start 0.67945 -0.305054)
			(end 0.12065 -0.305054)
			(stroke
				(width 0.1)
				(type default)
			)
			(layer "B.Fab")
		)
		(fp_line
			(start 0.12065 -0.305054)
			(end 0.12065 -0.2794)
			(stroke
				(width 0.1)
				(type default)
			)
			(layer "B.Fab")
		)
		(fp_line
			(start -0.12065 -0.3048)
			(end -0.67945 -0.3048)
			(stroke
				(width 0.1)
				(type default)
			)
			(layer "B.Fab")
		)
		(fp_line
			(start -0.67945 -0.3048)
			(end -0.67945 0.3048)
			(stroke
				(width 0.1)
				(type default)
			)
			(layer "B.Fab")
		)
		(fp_line
			(start 0.12065 -0.2794)
			(end -0.12065 -0.2794)
			(stroke
				(width 0.1)
				(type default)
			)
			(layer "B.Fab")
		)
		(fp_line
			(start -0.12065 -0.2794)
			(end -0.12065 -0.3048)
			(stroke
				(width 0.1)
				(type default)
			)
			(layer "B.Fab")
		)
		(fp_line
			(start 0.12065 0.2794)
			(end 0.12065 0.3048)
			(stroke
				(width 0.1)
				(type default)
			)
			(layer "B.Fab")
		)
		(fp_line
			(start -0.120396 0.2794)
			(end 0.12065 0.2794)
			(stroke
				(width 0.1)
				(type default)
			)
			(layer "B.Fab")
		)
		(fp_line
			(start 0.67945 0.3048)
			(end 0.67945 -0.305054)
			(stroke
				(width 0.1)
				(type default)
			)
			(layer "B.Fab")
		)
		(fp_line
			(start 0.12065 0.3048)
			(end 0.67945 0.3048)
			(stroke
				(width 0.1)
				(type default)
			)
			(layer "B.Fab")
		)
		(fp_line
			(start -0.120396 0.3048)
			(end -0.120396 0.2794)
			(stroke
				(width 0.1)
				(type default)
			)
			(layer "B.Fab")
		)
		(fp_line
			(start -0.67945 0.3048)
			(end -0.120396 0.3048)
			(stroke
				(width 0.1)
				(type default)
			)
			(layer "B.Fab")
		)
		(pad "1" smd circle
			(at 0.40005 0 270)
			(size 0 0)
			(layers "B.Cu" "B.Mask" "B.Paste")
			(net "FM_UARTSW_MSB_R_N")
		)
		(pad "2" smd circle
			(at -0.40005 0 270)
			(size 0 0)
			(layers "B.Cu" "B.Mask" "B.Paste")
			(net "FM_UARTSW_MSB_N")
		)
	)
	(footprint ""
		(layer "B.Cu")
		(at 40.889936 -51.38547 180)
		(property "Reference" "R280"
			(at 0 0 0)
			(layer "B.SilkS")
			(hide yes)
			(effects
				(font
					(size 1.27 1.27)
				)
				(justify mirror)
			)
		)
		(property "Value" ""
			(at 0 0 0)
			(layer "B.Fab")
			(effects
				(font
					(size 1.27 1.27)
				)
				(justify mirror)
			)
		)
		(duplicate_pad_numbers_are_jumpers no)
		(fp_line
			(start 0.7874 0.4064)
			(end 0.7874 -0.4064)
			(stroke
				(width 0.1524)
				(type default)
			)
			(layer "B.SilkS")
		)
		(fp_line
			(start 0.7874 -0.4064)
			(end -0.7874 -0.4064)
			(stroke
				(width 0.1524)
				(type default)
			)
			(layer "B.SilkS")
		)
		(fp_line
			(start -0.7874 0.4064)
			(end 0.7874 0.4064)
			(stroke
				(width 0.1524)
				(type default)
			)
			(layer "B.SilkS")
		)
		(fp_line
			(start -0.7874 -0.4064)
			(end -0.7874 0.4064)
			(stroke
				(width 0.1524)
				(type default)
			)
			(layer "B.SilkS")
		)
		(fp_line
			(start 0.67945 0.3048)
			(end 0.67945 -0.305054)
			(stroke
				(width 0.1)
				(type default)
			)
			(layer "B.Fab")
		)
		(fp_line
			(start 0.67945 -0.305054)
			(end 0.12065 -0.305054)
			(stroke
				(width 0.1)
				(type default)
			)
			(layer "B.Fab")
		)
		(fp_line
			(start 0.12065 0.3048)
			(end 0.67945 0.3048)
			(stroke
				(width 0.1)
				(type default)
			)
			(layer "B.Fab")
		)
		(fp_line
			(start 0.12065 0.2794)
			(end 0.12065 0.3048)
			(stroke
				(width 0.1)
				(type default)
			)
			(layer "B.Fab")
		)
		(fp_line
			(start 0.12065 -0.2794)
			(end -0.12065 -0.2794)
			(stroke
				(width 0.1)
				(type default)
			)
			(layer "B.Fab")
		)
		(fp_line
			(start 0.12065 -0.305054)
			(end 0.12065 -0.2794)
			(stroke
				(width 0.1)
				(type default)
			)
			(layer "B.Fab")
		)
		(fp_line
			(start -0.120396 0.3048)
			(end -0.120396 0.2794)
			(stroke
				(width 0.1)
				(type default)
			)
			(layer "B.Fab")
		)
		(fp_line
			(start -0.120396 0.2794)
			(end 0.12065 0.2794)
			(stroke
				(width 0.1)
				(type default)
			)
			(layer "B.Fab")
		)
		(fp_line
			(start -0.12065 -0.2794)
			(end -0.12065 -0.3048)
			(stroke
				(width 0.1)
				(type default)
			)
			(layer "B.Fab")
		)
		(fp_line
			(start -0.12065 -0.3048)
			(end -0.67945 -0.3048)
			(stroke
				(width 0.1)
				(type default)
			)
			(layer "B.Fab")
		)
		(fp_line
			(start -0.67945 0.3048)
			(end -0.120396 0.3048)
			(stroke
				(width 0.1)
				(type default)
			)
			(layer "B.Fab")
		)
		(fp_line
			(start -0.67945 -0.3048)
			(end -0.67945 0.3048)
			(stroke
				(width 0.1)
				(type default)
			)
			(layer "B.Fab")
		)
		(pad "1" smd circle
			(at 0.40005 0)
			(size 0 0)
			(layers "B.Cu" "B.Mask" "B.Paste")
			(net "P1V2_AUX")
		)
		(pad "2" smd circle
			(at -0.40005 0)
			(size 0 0)
			(layers "B.Cu" "B.Mask" "B.Paste")
			(net "P1V2_P1V0_I3C_VDDL2")
		)
	)
	(footprint ""
		(layer "B.Cu")
		(at 56.173116 -74.242676 90)
		(property "Reference" "C309"
			(at 0 0 90)
			(layer "B.SilkS")
			(hide yes)
			(effects
				(font
					(size 1.27 1.27)
				)
				(justify mirror)
			)
		)
		(property "Value" ""
			(at 0 0 90)
			(layer "B.Fab")
			(effects
				(font
					(size 1.27 1.27)
				)
				(justify mirror)
			)
		)
		(duplicate_pad_numbers_are_jumpers no)
		(fp_line
			(start 0.7874 -0.4064)
			(end -0.7874 -0.4064)
			(stroke
				(width 0.1524)
				(type default)
			)
			(layer "B.SilkS")
		)
		(fp_line
			(start -0.7874 -0.4064)
			(end -0.7874 0.4064)
			(stroke
				(width 0.1524)
				(type default)
			)
			(layer "B.SilkS")
		)
		(fp_line
			(start 0.7874 0.4064)
			(end 0.7874 -0.4064)
			(stroke
				(width 0.1524)
				(type default)
			)
			(layer "B.SilkS")
		)
		(fp_line
			(start -0.7874 0.4064)
			(end 0.7874 0.4064)
			(stroke
				(width 0.1524)
				(type default)
			)
			(layer "B.SilkS")
		)
		(fp_line
			(start 0.67945 -0.305054)
			(end 0.12065 -0.305054)
			(stroke
				(width 0.1)
				(type default)
			)
			(layer "B.Fab")
		)
		(fp_line
			(start 0.12065 -0.305054)
			(end 0.12065 -0.2794)
			(stroke
				(width 0.1)
				(type default)
			)
			(layer "B.Fab")
		)
		(fp_line
			(start -0.12065 -0.3048)
			(end -0.67945 -0.3048)
			(stroke
				(width 0.1)
				(type default)
			)
			(layer "B.Fab")
		)
		(fp_line
			(start -0.67945 -0.3048)
			(end -0.67945 0.3048)
			(stroke
				(width 0.1)
				(type default)
			)
			(layer "B.Fab")
		)
		(fp_line
			(start 0.12065 -0.2794)
			(end -0.12065 -0.2794)
			(stroke
				(width 0.1)
				(type default)
			)
			(layer "B.Fab")
		)
		(fp_line
			(start -0.12065 -0.2794)
			(end -0.12065 -0.3048)
			(stroke
				(width 0.1)
				(type default)
			)
			(layer "B.Fab")
		)
		(fp_line
			(start 0.12065 0.2794)
			(end 0.12065 0.3048)
			(stroke
				(width 0.1)
				(type default)
			)
			(layer "B.Fab")
		)
		(fp_line
			(start -0.120396 0.2794)
			(end 0.12065 0.2794)
			(stroke
				(width 0.1)
				(type default)
			)
			(layer "B.Fab")
		)
		(fp_line
			(start 0.67945 0.3048)
			(end 0.67945 -0.305054)
			(stroke
				(width 0.1)
				(type default)
			)
			(layer "B.Fab")
		)
		(fp_line
			(start 0.12065 0.3048)
			(end 0.67945 0.3048)
			(stroke
				(width 0.1)
				(type default)
			)
			(layer "B.Fab")
		)
		(fp_line
			(start -0.120396 0.3048)
			(end -0.120396 0.2794)
			(stroke
				(width 0.1)
				(type default)
			)
			(layer "B.Fab")
		)
		(fp_line
			(start -0.67945 0.3048)
			(end -0.120396 0.3048)
			(stroke
				(width 0.1)
				(type default)
			)
			(layer "B.Fab")
		)
		(pad "1" smd circle
			(at 0.40005 0 270)
			(size 0 0)
			(layers "B.Cu" "B.Mask" "B.Paste")
			(net "P1V2_SENSOR")
		)
		(pad "2" smd circle
			(at -0.40005 0 270)
			(size 0 0)
			(layers "B.Cu" "B.Mask" "B.Paste")
			(net "GND")
		)
	)
	(footprint ""
		(layer "B.Cu")
		(at 43.1038 -62.1792 90)
		(property "Reference" "R235"
			(at 0 0 90)
			(layer "B.SilkS")
			(hide yes)
			(effects
				(font
					(size 1.27 1.27)
				)
				(justify mirror)
			)
		)
		(property "Value" ""
			(at 0 0 90)
			(layer "B.Fab")
			(effects
				(font
					(size 1.27 1.27)
				)
				(justify mirror)
			)
		)
		(duplicate_pad_numbers_are_jumpers no)
		(fp_line
			(start 0.7874 -0.4064)
			(end -0.7874 -0.4064)
			(stroke
				(width 0.1524)
				(type default)
			)
			(layer "B.SilkS")
		)
		(fp_line
			(start -0.7874 -0.4064)
			(end -0.7874 0.4064)
			(stroke
				(width 0.1524)
				(type default)
			)
			(layer "B.SilkS")
		)
		(fp_line
			(start 0.7874 0.4064)
			(end 0.7874 -0.4064)
			(stroke
				(width 0.1524)
				(type default)
			)
			(layer "B.SilkS")
		)
		(fp_line
			(start -0.7874 0.4064)
			(end 0.7874 0.4064)
			(stroke
				(width 0.1524)
				(type default)
			)
			(layer "B.SilkS")
		)
		(fp_line
			(start 0.67945 -0.305054)
			(end 0.12065 -0.305054)
			(stroke
				(width 0.1)
				(type default)
			)
			(layer "B.Fab")
		)
		(fp_line
			(start 0.12065 -0.305054)
			(end 0.12065 -0.2794)
			(stroke
				(width 0.1)
				(type default)
			)
			(layer "B.Fab")
		)
		(fp_line
			(start -0.12065 -0.3048)
			(end -0.67945 -0.3048)
			(stroke
				(width 0.1)
				(type default)
			)
			(layer "B.Fab")
		)
		(fp_line
			(start -0.67945 -0.3048)
			(end -0.67945 0.3048)
			(stroke
				(width 0.1)
				(type default)
			)
			(layer "B.Fab")
		)
		(fp_line
			(start 0.12065 -0.2794)
			(end -0.12065 -0.2794)
			(stroke
				(width 0.1)
				(type default)
			)
			(layer "B.Fab")
		)
		(fp_line
			(start -0.12065 -0.2794)
			(end -0.12065 -0.3048)
			(stroke
				(width 0.1)
				(type default)
			)
			(layer "B.Fab")
		)
		(fp_line
			(start 0.12065 0.2794)
			(end 0.12065 0.3048)
			(stroke
				(width 0.1)
				(type default)
			)
			(layer "B.Fab")
		)
		(fp_line
			(start -0.120396 0.2794)
			(end 0.12065 0.2794)
			(stroke
				(width 0.1)
				(type default)
			)
			(layer "B.Fab")
		)
		(fp_line
			(start 0.67945 0.3048)
			(end 0.67945 -0.305054)
			(stroke
				(width 0.1)
				(type default)
			)
			(layer "B.Fab")
		)
		(fp_line
			(start 0.12065 0.3048)
			(end 0.67945 0.3048)
			(stroke
				(width 0.1)
				(type default)
			)
			(layer "B.Fab")
		)
		(fp_line
			(start -0.120396 0.3048)
			(end -0.120396 0.2794)
			(stroke
				(width 0.1)
				(type default)
			)
			(layer "B.Fab")
		)
		(fp_line
			(start -0.67945 0.3048)
			(end -0.120396 0.3048)
			(stroke
				(width 0.1)
				(type default)
			)
			(layer "B.Fab")
		)
		(pad "1" smd circle
			(at 0.40005 0 270)
			(size 0 0)
			(layers "B.Cu" "B.Mask" "B.Paste")
			(net "GND")
		)
		(pad "2" smd circle
			(at -0.40005 0 270)
			(size 0 0)
			(layers "B.Cu" "B.Mask" "B.Paste")
			(net "A_BMC_DACREST")
		)
	)
	(footprint ""
		(layer "B.Cu")
		(at 80.512666 -49.261776 90)
		(property "Reference" "C2"
			(at 0 0 90)
			(layer "B.SilkS")
			(hide yes)
			(effects
				(font
					(size 1.27 1.27)
				)
				(justify mirror)
			)
		)
		(property "Value" ""
			(at 0 0 90)
			(layer "B.Fab")
			(effects
				(font
					(size 1.27 1.27)
				)
				(justify mirror)
			)
		)
		(duplicate_pad_numbers_are_jumpers no)
		(fp_line
			(start 0.7874 -0.4064)
			(end -0.7874 -0.4064)
			(stroke
				(width 0.1524)
				(type default)
			)
			(layer "B.SilkS")
		)
		(fp_line
			(start -0.7874 -0.4064)
			(end -0.7874 0.4064)
			(stroke
				(width 0.1524)
				(type default)
			)
			(layer "B.SilkS")
		)
		(fp_line
			(start 0.7874 0.4064)
			(end 0.7874 -0.4064)
			(stroke
				(width 0.1524)
				(type default)
			)
			(layer "B.SilkS")
		)
		(fp_line
			(start -0.7874 0.4064)
			(end 0.7874 0.4064)
			(stroke
				(width 0.1524)
				(type default)
			)
			(layer "B.SilkS")
		)
		(fp_line
			(start 0.67945 -0.305054)
			(end 0.12065 -0.305054)
			(stroke
				(width 0.1)
				(type default)
			)
			(layer "B.Fab")
		)
		(fp_line
			(start 0.12065 -0.305054)
			(end 0.12065 -0.2794)
			(stroke
				(width 0.1)
				(type default)
			)
			(layer "B.Fab")
		)
		(fp_line
			(start -0.12065 -0.3048)
			(end -0.67945 -0.3048)
			(stroke
				(width 0.1)
				(type default)
			)
			(layer "B.Fab")
		)
		(fp_line
			(start -0.67945 -0.3048)
			(end -0.67945 0.3048)
			(stroke
				(width 0.1)
				(type default)
			)
			(layer "B.Fab")
		)
		(fp_line
			(start 0.12065 -0.2794)
			(end -0.12065 -0.2794)
			(stroke
				(width 0.1)
				(type default)
			)
			(layer "B.Fab")
		)
		(fp_line
			(start -0.12065 -0.2794)
			(end -0.12065 -0.3048)
			(stroke
				(width 0.1)
				(type default)
			)
			(layer "B.Fab")
		)
		(fp_line
			(start 0.12065 0.2794)
			(end 0.12065 0.3048)
			(stroke
				(width 0.1)
				(type default)
			)
			(layer "B.Fab")
		)
		(fp_line
			(start -0.120396 0.2794)
			(end 0.12065 0.2794)
			(stroke
				(width 0.1)
				(type default)
			)
			(layer "B.Fab")
		)
		(fp_line
			(start 0.67945 0.3048)
			(end 0.67945 -0.305054)
			(stroke
				(width 0.1)
				(type default)
			)
			(layer "B.Fab")
		)
		(fp_line
			(start 0.12065 0.3048)
			(end 0.67945 0.3048)
			(stroke
				(width 0.1)
				(type default)
			)
			(layer "B.Fab")
		)
		(fp_line
			(start -0.120396 0.3048)
			(end -0.120396 0.2794)
			(stroke
				(width 0.1)
				(type default)
			)
			(layer "B.Fab")
		)
		(fp_line
			(start -0.67945 0.3048)
			(end -0.120396 0.3048)
			(stroke
				(width 0.1)
				(type default)
			)
			(layer "B.Fab")
		)
		(pad "1" smd circle
			(at 0.40005 0 270)
			(size 0 0)
			(layers "B.Cu" "B.Mask" "B.Paste")
			(net "P1V2_AUX")
		)
		(pad "2" smd circle
			(at -0.40005 0 270)
			(size 0 0)
			(layers "B.Cu" "B.Mask" "B.Paste")
			(net "GND")
		)
	)
	(footprint ""
		(layer "B.Cu")
		(at 50.54346 -61.852048 90)
		(property "Reference" "C133"
			(at 0 0 90)
			(layer "B.SilkS")
			(hide yes)
			(effects
				(font
					(size 1.27 1.27)
				)
				(justify mirror)
			)
		)
		(property "Value" ""
			(at 0 0 90)
			(layer "B.Fab")
			(effects
				(font
					(size 1.27 1.27)
				)
				(justify mirror)
			)
		)
		(duplicate_pad_numbers_are_jumpers no)
		(fp_line
			(start 0.7874 -0.4064)
			(end -0.7874 -0.4064)
			(stroke
				(width 0.1524)
				(type default)
			)
			(layer "B.SilkS")
		)
		(fp_line
			(start -0.7874 -0.4064)
			(end -0.7874 0.4064)
			(stroke
				(width 0.1524)
				(type default)
			)
			(layer "B.SilkS")
		)
		(fp_line
			(start 0.7874 0.4064)
			(end 0.7874 -0.4064)
			(stroke
				(width 0.1524)
				(type default)
			)
			(layer "B.SilkS")
		)
		(fp_line
			(start -0.7874 0.4064)
			(end 0.7874 0.4064)
			(stroke
				(width 0.1524)
				(type default)
			)
			(layer "B.SilkS")
		)
		(fp_line
			(start 0.67945 -0.305054)
			(end 0.12065 -0.305054)
			(stroke
				(width 0.1)
				(type default)
			)
			(layer "B.Fab")
		)
		(fp_line
			(start 0.12065 -0.305054)
			(end 0.12065 -0.2794)
			(stroke
				(width 0.1)
				(type default)
			)
			(layer "B.Fab")
		)
		(fp_line
			(start -0.12065 -0.3048)
			(end -0.67945 -0.3048)
			(stroke
				(width 0.1)
				(type default)
			)
			(layer "B.Fab")
		)
		(fp_line
			(start -0.67945 -0.3048)
			(end -0.67945 0.3048)
			(stroke
				(width 0.1)
				(type default)
			)
			(layer "B.Fab")
		)
		(fp_line
			(start 0.12065 -0.2794)
			(end -0.12065 -0.2794)
			(stroke
				(width 0.1)
				(type default)
			)
			(layer "B.Fab")
		)
		(fp_line
			(start -0.12065 -0.2794)
			(end -0.12065 -0.3048)
			(stroke
				(width 0.1)
				(type default)
			)
			(layer "B.Fab")
		)
		(fp_line
			(start 0.12065 0.2794)
			(end 0.12065 0.3048)
			(stroke
				(width 0.1)
				(type default)
			)
			(layer "B.Fab")
		)
		(fp_line
			(start -0.120396 0.2794)
			(end 0.12065 0.2794)
			(stroke
				(width 0.1)
				(type default)
			)
			(layer "B.Fab")
		)
		(fp_line
			(start 0.67945 0.3048)
			(end 0.67945 -0.305054)
			(stroke
				(width 0.1)
				(type default)
			)
			(layer "B.Fab")
		)
		(fp_line
			(start 0.12065 0.3048)
			(end 0.67945 0.3048)
			(stroke
				(width 0.1)
				(type default)
			)
			(layer "B.Fab")
		)
		(fp_line
			(start -0.120396 0.3048)
			(end -0.120396 0.2794)
			(stroke
				(width 0.1)
				(type default)
			)
			(layer "B.Fab")
		)
		(fp_line
			(start -0.67945 0.3048)
			(end -0.120396 0.3048)
			(stroke
				(width 0.1)
				(type default)
			)
			(layer "B.Fab")
		)
		(pad "1" smd circle
			(at 0.40005 0 270)
			(size 0 0)
			(layers "B.Cu" "B.Mask" "B.Paste")
			(net "GND")
		)
		(pad "2" smd circle
			(at -0.40005 0 270)
			(size 0 0)
			(layers "B.Cu" "B.Mask" "B.Paste")
			(net "A_BMC_ADCVREFN1")
		)
	)
)
